FILE_TYPE = MULTI_PHYS_TABLE;

PART 'Q_OSC4P'

{========================================================================================}
:VALUE       | PACK_TYPE | MATERIAL | PART_NUMBER              = STANDARD        | LIFECYCLE      | PART_NUMBER              | JEDEC_TYPE                 | CLASS | DESCRIPTION                                | COMPONENT_TYPE | LPID | CREATEDAY  ;
{========================================================================================}
 '24MHZ'     | 'SMLF'    | 'OSC'    | 'TMP_QBF624000001'(!)    = ''              | ''             | 'BF624000001'            |'OSC4_7X'| 'IC'  | 'OSC SMD 24MHZ(50PPM,15PF,2.8V)7X24000023' | 'SMTOTHER'     | ''   | ''        
 '24MHZ'     | 'SM'      | 'EMPTY'  | 'TMP_QBF624000001'(!)    = ''              | ''             | 'BF624000001'            |'OSC4_7X'| 'IC'  | 'OSC SMD 24MHZ(50PPM,15PF,2.8V)7X24000023' | 'SMTOTHER'     | ''   | ''        
 '156.25MHZ' | 'SMLF'    | 'OSC'    | 'TMP-C_LU2_EASON_2'(!)   = ''              | ''             | 'TMP-C_LU2_EASON_2'      |'OSC4_VFAC3'| 'IC'  | 'OSC SMD 156.25M(50PPM,3.3V)VFAC3BHL-1-15' | 'SMTOTHER'     | ''   | ''        
 '156.25MHZ' | 'SM'      | 'EMPTY'  | 'TMP-C_LU2_EASON_2'(!)   = ''              | ''             | 'TMP-C_LU2_EASON_2'      |'OSC4_VFAC3'| 'IC'  | 'OSC SMD 156.25M(50PPM,3.3V)VFAC3BHL-1-15' | 'SMTOTHER'     | ''   | ''        
 '1.84MHZ'   | 'SMLF'    | 'OSC'    | 'QN-BF518432306'(!)      = ''              | ''             | 'BF518432306'            |'OSC4_C-XOA'| 'IC'  | 'OSC SMD 1.8432MHZ(+-30PPM,3.3V)'          | 'SMTOTHER'     | ''   | ''        
 '1.84MHZ'   | 'SM'      | 'EMPTY'  | 'QN-BF518432306'(!)      = ''              | ''             | 'BF518432306'            |'OSC4_C-XOA'| 'IC'  | 'OSC SMD 1.8432MHZ(+-30PPM,3.3V)'          | 'SMTOTHER'     | ''   | ''        
 '156.25MHZ' | 'SMLF'    | 'OSC'    | 'TMP-C_LU2_EASON_0417_1'(!) = ''              | ''             | 'TMP-C_LU2_EASON_0417_1' |'OSC4_HXO'| 'IC'  | 'OSC SMD 156.25MHZ(50PPM,3.3V)'            | 'SMTOTHER'     | ''   | ''        
 '156.25MHZ' | 'SM'      | 'EMPTY'  | 'TMP-C_LU2_EASON_0417_1'(!) = ''              | ''             | 'TMP-C_LU2_EASON_0417_1' |'OSC4_HXO'| 'IC'  | 'OSC SMD 156.25MHZ(50PPM,3.3V)'            | 'SMTOTHER'     | ''   | ''        
 '48MHz'     | 'SMLF'    | 'OSC'    | 'TMP_QBF648000601'(!)    = ''              | 'End of Life'    | 'BF648000601'            |'OSC4_7W_EOL'| 'IC'  | 'OSC SMD 48MHZ(+-25PPM,3.3V)7W48000078 EU' | 'SMTOTHER'     | ''   | ''        
 '48MHz'     | 'SM'      | 'EMPTY'  | 'TMP_QBF648000601'(!)    = ''              | 'End of Life'    | 'BF648000601'            |'OSC4_7W_EOL'| 'IC'  | 'OSC SMD 48MHZ(+-25PPM,3.3V)7W48000078 EU' | 'SMTOTHER'     | ''   | ''        
 '156.25MHz' | 'SMLF'    | 'OSC'    | 'QN-BF715625010'(!)      = ''              | 'End of Life'    | 'BF715625010'            |'OSC4_C-XOA_EOL'| 'IC'  | 'OSC SMD 156.25MHZ(50PPM,3.3V)7WA5600005'  | 'SMTOTHER'     | ''   | ''        
 '156.25MHz' | 'SM'      | 'EMPTY'  | 'QN-BF715625010'(!)      = ''              | 'End of Life'    | 'BF715625010'            |'OSC4_C-XOA_EOL'| 'IC'  | 'OSC SMD 156.25MHZ(50PPM,3.3V)7WA5600005'  | 'SMTOTHER'     | ''   | ''        
 '33.333MHZ' | 'SMLF'    | 'OSC'    | 'TMP-C_LU2_EASON_0916_1'(!) = ''              | ''             | 'TMP-C_LU2_EASON_0916_1' |'X_7C'| 'IC'  | 'OSC SMD 33.333MHZ 20PPM,3.3V)7C33300016'  | 'SMTOTHER'     | ''   | ''        
 '33.333MHZ' | 'SM'      | 'EMPTY'  | 'TMP-C_LU2_EASON_0916_1'(!) = ''              | ''             | 'TMP-C_LU2_EASON_0916_1' |'X_7C'| 'IC'  | 'OSC SMD 33.333MHZ 20PPM,3.3V)7C33300016'  | 'SMTOTHER'     | ''   | ''        
 '25MHZ'     | 'SMLF'    | 'OSC'    | 'BF625000002'(!)         = 'End of Design'  | 'Comp-Approve'   | 'BF625000002'            |'OSC4_DSO221SRAC'| 'IC'  | 'OSCILLATOR SMD 25MHZ(+-30PPM,3.3V)DSO221' | 'SMTOTHER'     | ''   | ''        
 '25MHZ'     | 'SM'      | 'EMPTY'  | 'BF625000002'(!)         = 'End of Design'  | 'Comp-Approve'   | 'BF625000002'            |'OSC4_DSO221SRAC'| 'IC'  | 'OSCILLATOR SMD 25MHZ(+-30PPM,3.3V)DSO221' | 'SMTOTHER'     | ''   | ''        
 '50MHZ'     | 'SMLF'    | 'OSC'    | 'BF650000003'(!)         = 'End of Design'  | 'Comp-Approve'   | 'BF650000003'            |'OSC_DSO321SR'| 'IC'  | 'OSC SMD 50MHZ(+-50PPM,3.3V)1XSE050000AR4' | 'SMTOTHER'     | ''   | ''        
 '50MHZ'     | 'SM'      | 'EMPTY'  | 'BF650000003'(!)         = 'End of Design'  | 'Comp-Approve'   | 'BF650000003'            |'OSC_DSO321SR'| 'IC'  | 'OSC SMD 50MHZ(+-50PPM,3.3V)1XSE050000AR4' | 'SMTOTHER'     | ''   | ''        
 '25MHz'     | 'SMLF'    | 'OSC'    | 'BF625000003'(!)         = ''              | 'End of Life'    | 'BF625000003'            |'OSC4_FNXA_EOL'| 'IC'  | 'OSC SMD 25MHZ(+-50PPM.3.3V)7W25000025'    | 'SMTOTHER'     | ''   | ''        
 '25MHz'     | 'SM'      | 'EMPTY'  | 'BF625000003'(!)         = ''              | 'End of Life'    | 'BF625000003'            |'OSC4_FNXA_EOL'| 'IC'  | 'OSC SMD 25MHZ(+-50PPM.3.3V)7W25000025'    | 'SMTOTHER'     | ''   | ''        
 '25MHz'     | 'SMLF'    | 'OSC'    | 'BF625000014'(!)         = ''              | ''             | 'BF625000014'            |'OSC4_FJ2500009'| 'IC'  | 'OSC SMD 25MHZ(+-25PPM,3.3V)FJ2500009'     | 'SMTOTHER'     | ''   | ''        
 '25MHz'     | 'SM'      | 'EMPTY'  | 'BF625000014'(!)         = ''              | ''             | 'BF625000014'            |'OSC4_FJ2500009'| 'IC'  | 'OSC SMD 25MHZ(+-25PPM,3.3V)FJ2500009'     | 'SMTOTHER'     | ''   | ''        
 '32.768KHZ' | 'SMLF'    | 'OSC'    | 'BF332768008'(!)         = ''              | ''             | 'BF332768008'            |'OSC4_7C'| 'IC'  | 'OSC 32.768KHZ(+-25PPM)D57A0.03276MNS'     | 'SMTOTHER'     | ''   | ''        
 '32.768KHZ' | 'SM'      | 'EMPTY'  | 'BF332768008'(!)         = ''              | ''             | 'BF332768008'            |'OSC4_7C'| 'IC'  | 'OSC 32.768KHZ(+-25PPM)D57A0.03276MNS'     | 'SMTOTHER'     | ''   | ''        
 '32.768KHZ' | 'SMLF'    | 'OSC'    | 'BF332768012'(!)         = ''              | ''             | 'BF332768012'            |'OSC4_7XXA'| 'IC'  | 'OSC SMD 32.768KHZ(30PPM,1.8V)7XZ3270002'  | 'SMTOTHER'     | ''   | ''        
 '32.768KHZ' | 'SM'      | 'EMPTY'  | 'BF332768012'(!)         = ''              | ''             | 'BF332768012'            |'OSC4_7XXA'| 'IC'  | 'OSC SMD 32.768KHZ(30PPM,1.8V)7XZ3270002'  | 'SMTOTHER'     | ''   | ''        
 '40MHZ'     | 'SMLF'    | 'OSC'    | 'BF640000001'(!)         = ''              | ''             | 'BF640000001'            |'OSC4_FNXA'| 'IC'  | 'OSC SMD 40MHZ(+-25PPM,50PF)7W40000101'    | 'SMTOTHER'     | ''   | ''        
 '40MHZ'     | 'SM'      | 'EMPTY'  | 'BF640000001'(!)         = ''              | ''             | 'BF640000001'            |'OSC4_FNXA'| 'IC'  | 'OSC SMD 40MHZ(+-25PPM,50PF)7W40000101'    | 'SMTOTHER'     | ''   | ''        
 '50MHZ'     | 'SMLF'    | 'OSC'    | 'BF650000002'(!)         = 'End of Design'  | 'Comp-Approve'   | 'BF650000002'            |'OSC4_7X'| 'IC'  | 'OSC SMD 50MHZ(+-50PPM,3.3V,7X50000017)'   | 'SMTOTHER'     | ''   | '20120913'
 '50MHZ'     | 'SM'      | 'EMPTY'  | 'BF650000002'(!)         = 'End of Design'  | 'Comp-Approve'   | 'BF650000002'            |'OSC4_7X'| 'IC'  | 'OSC SMD 50MHZ(+-50PPM,3.3V,7X50000017)'   | 'SMTOTHER'     | ''   | '20120913'
 '50MHZ'     | 'SMLF'    | 'OSC'    | 'BF650000032'(!)         = ''              | ''             | 'BF650000032'            |'OSC4_XP'| 'IC'  | 'OSC SMD 50MHZ(25PPM,15PF,3.3V)FK5000023'  | 'SMTOTHER'     | ''   | '20130129'
 '50MHZ'     | 'SM'      | 'EMPTY'  | 'BF650000032'(!)         = ''              | ''             | 'BF650000032'            |'OSC4_XP'| 'IC'  | 'OSC SMD 50MHZ(25PPM,15PF,3.3V)FK5000023'  | 'SMTOTHER'     | ''   | '20130129'
 '50MHZ'     | 'SMLF'    | 'OSC'    | 'BF650000009'(!)         = ''              | 'End of Life'    | 'BF650000009'            |'OSC4_FN_EOL'| 'IC'  | 'OSC SMD 50MHZ(25PPM.3.3V.D36A50.0000MTS)' | 'SMTOTHER'     | ''   | '20130515'
 '50MHZ'     | 'SM'      | 'EMPTY'  | 'BF650000009'(!)         = ''              | 'End of Life'    | 'BF650000009'            |'OSC4_FN_EOL'| 'IC'  | 'OSC SMD 50MHZ(25PPM.3.3V.D36A50.0000MTS)' | 'SMTOTHER'     | ''   | '20130515'
 '50MHZ'     | 'SMLF'    | 'OSC'    | 'BF650000041'(!)         = ''              | ''             | 'BF650000041'            |'OSC4_7XXA'| 'IC'  | 'OSC SMD 50MHZ(+-50PPM,15PF)7X50000016'    | 'SMTOTHER'     | ''   | '20140226'
 '50MHZ'     | 'SM'      | 'EMPTY'  | 'BF650000041'(!)         = ''              | ''             | 'BF650000041'            |'OSC4_7XXA'| 'IC'  | 'OSC SMD 50MHZ(+-50PPM,15PF)7X50000016'    | 'SMTOTHER'     | ''   | '20140226'
 '25MHZ'     | 'SMLF'    | 'OSC'    | 'BF625000021'(!)         = ''              | ''             | 'BF625000021'            |'OSC4_DNCA250000ETS_2-5X2'| 'IC'  | 'OSC SMD 25MHZ(+-25PPM,3.3V)DNCA25.0000ET' | 'SMTOTHER'     | ''   | '20150311'
 '25MHZ'     | 'SM'      | 'EMPTY'  | 'BF625000021'(!)         = ''              | ''             | 'BF625000021'            |'OSC4_DNCA250000ETS_2-5X2'| 'IC'  | 'OSC SMD 25MHZ(+-25PPM,3.3V)DNCA25.0000ET' | 'SMTOTHER'     | ''   | '20150311'
 '50MHZ'     | 'SMLF'    | 'OSC'    | 'BF650000050'(!)         = ''              | ''             | 'BF650000050'            |'OSC4_7XXA'| 'IC'  | 'OSC SMD 50MHZ(20PPM,2.5V)7X50000024'      | 'SMTOTHER'     | ''   | '20151210'
 '50MHZ'     | 'SM'      | 'EMPTY'  | 'BF650000050'(!)         = ''              | ''             | 'BF650000050'            |'OSC4_7XXA'| 'IC'  | 'OSC SMD 50MHZ(20PPM,2.5V)7X50000024'      | 'SMTOTHER'     | ''   | '20151210'
 '50MHZ'     | 'SMLF'    | 'OSC'    | 'BF650000055'(!)         = ''               | ''               | 'BF650000055'            |'OSC4_XP'| 'IC'  | 'OSC SMD 50MHZ(+-25PPM, 3.3V)AEC'          | 'SMTOTHER'     | ''   | '20160426'
 '50MHZ'     | 'SM'      | 'EMPTY'  | 'BF650000055'(!)         = ''               | ''               | 'BF650000055'            |'OSC4_XP'| 'IC'  | 'OSC SMD 50MHZ(+-25PPM, 3.3V)AEC'          | 'SMTOTHER'     | ''   | '20160426'

END_PART

END.

